# T6G (Grand Teton) — schematic netlist excerpt (pin names and nets, part order shuffled) for the footprints in the layout excerpt that follows; sources: Cadence DE-HDL packaged netlist, KiCad conversion of 04192023_DAF0TMB3IC0_F0TG_MB_C_brd_V02_OCP.brd

PR2513  Q_RES  1 1% CHIP  pkg 0402LF  page 266 : A = P12V_HSC_ADC_P ; B = P12V_HSC_SENSE2_R4_P
R5031  Q_RES  4.7K 5% EMPTY  pkg 0402LF  page 55 : A = GND ; B = FM_BMC_READY_N

(kicad_pcb
	(version 20260206)
	(generator "pcbnew")
	(generator_version "10.0")
	(general
		(thickness 1.6)
		(legacy_teardrops no)
	)
	(paper "A4")
	(title_block
		(title "04192023_DAF0TMB3IC0_F0TG_MB_C_brd_V02_OCP.brd")
		(comment 1 "Grand Teton / footprints 5301-5302 of 8354")
	)
	(layers
		(0 "F.Cu" signal "TOP")
		(4 "In1.Cu" signal "GND")
		(6 "In2.Cu" signal "IN1")
		(8 "In3.Cu" signal "GND1")
		(10 "In4.Cu" signal "IN2")
		(12 "In5.Cu" signal "GND2")
		(14 "In6.Cu" signal "IN3")
		(16 "In7.Cu" signal "GND3")
		(18 "In8.Cu" signal "VCC")
		(20 "In9.Cu" signal "VCC1")
		(22 "In10.Cu" signal "GND4")
		(24 "In11.Cu" signal "IN4")
		(26 "In12.Cu" signal "GND5")
		(28 "In13.Cu" signal "IN5")
		(30 "In14.Cu" signal "GND6")
		(32 "In15.Cu" signal "IN6")
		(34 "In16.Cu" signal "GND7")
		(2 "B.Cu" signal "BOTTOM")
		(9 "F.Adhes" user "F.Adhesive")
		(11 "B.Adhes" user "B.Adhesive")
		(13 "F.Paste" user "Package Geometry/Pastemask Top")
		(15 "B.Paste" user "Package Geometry/Pastemask Bottom")
		(5 "F.SilkS" user "Ref Des/Silkscreen Top")
		(7 "B.SilkS" user "Ref Des/Silkscreen Bottom")
		(1 "F.Mask" user "Board Geometry/Soldermask Top")
		(3 "B.Mask" user "Board Geometry/Soldermask Bottom")
		(17 "Dwgs.User" user "User.Drawings")
		(19 "Cmts.User" user "User.Comments")
		(21 "Eco1.User" user "User.Eco1")
		(23 "Eco2.User" user "User.Eco2")
		(25 "Edge.Cuts" user "Board Geometry/Outline")
		(27 "Margin" user)
		(31 "F.CrtYd" user "Package Geometry/Place Bound Top")
		(29 "B.CrtYd" user "Package Geometry/Place Bound Bottom")
		(35 "F.Fab" user "Ref Des/Assembly Top")
		(33 "B.Fab" user "Ref Des/Assembly Bottom")
	)
	(footprint ""
		(layer "B.Cu")
		(at 208.461356 -382.596136)
		(property "Reference" "PR2513"
			(at 0 0 0)
			(layer "B.SilkS")
			(hide yes)
			(effects
				(font
					(size 1.27 1.27)
				)
				(justify mirror)
			)
		)
		(property "Value" ""
			(at 0 0 0)
			(layer "B.Fab")
			(effects
				(font
					(size 1.27 1.27)
				)
				(justify mirror)
			)
		)
		(duplicate_pad_numbers_are_jumpers no)
		(fp_line
			(start -0.7874 -0.4064)
			(end -0.7874 0.4064)
			(stroke
				(width 0.1524)
				(type default)
			)
			(layer "B.SilkS")
		)
		(fp_line
			(start -0.7874 0.4064)
			(end 0.7874 0.4064)
			(stroke
				(width 0.1524)
				(type default)
			)
			(layer "B.SilkS")
		)
		(fp_line
			(start 0.7874 -0.4064)
			(end -0.7874 -0.4064)
			(stroke
				(width 0.1524)
				(type default)
			)
			(layer "B.SilkS")
		)
		(fp_line
			(start 0.7874 0.4064)
			(end 0.7874 -0.4064)
			(stroke
				(width 0.1524)
				(type default)
			)
			(layer "B.SilkS")
		)
		(fp_line
			(start -0.67945 -0.3048)
			(end -0.67945 0.3048)
			(stroke
				(width 0.1)
				(type default)
			)
			(layer "B.Fab")
		)
		(fp_line
			(start -0.67945 0.3048)
			(end -0.120396 0.3048)
			(stroke
				(width 0.1)
				(type default)
			)
			(layer "B.Fab")
		)
		(fp_line
			(start -0.12065 -0.3048)
			(end -0.67945 -0.3048)
			(stroke
				(width 0.1)
				(type default)
			)
			(layer "B.Fab")
		)
		(fp_line
			(start -0.12065 -0.2794)
			(end -0.12065 -0.3048)
			(stroke
				(width 0.1)
				(type default)
			)
			(layer "B.Fab")
		)
		(fp_line
			(start -0.120396 0.2794)
			(end 0.12065 0.2794)
			(stroke
				(width 0.1)
				(type default)
			)
			(layer "B.Fab")
		)
		(fp_line
			(start -0.120396 0.3048)
			(end -0.120396 0.2794)
			(stroke
				(width 0.1)
				(type default)
			)
			(layer "B.Fab")
		)
		(fp_line
			(start 0.12065 -0.305054)
			(end 0.12065 -0.2794)
			(stroke
				(width 0.1)
				(type default)
			)
			(layer "B.Fab")
		)
		(fp_line
			(start 0.12065 -0.2794)
			(end -0.12065 -0.2794)
			(stroke
				(width 0.1)
				(type default)
			)
			(layer "B.Fab")
		)
		(fp_line
			(start 0.12065 0.2794)
			(end 0.12065 0.3048)
			(stroke
				(width 0.1)
				(type default)
			)
			(layer "B.Fab")
		)
		(fp_line
			(start 0.12065 0.3048)
			(end 0.67945 0.3048)
			(stroke
				(width 0.1)
				(type default)
			)
			(layer "B.Fab")
		)
		(fp_line
			(start 0.67945 -0.305054)
			(end 0.12065 -0.305054)
			(stroke
				(width 0.1)
				(type default)
			)
			(layer "B.Fab")
		)
		(fp_line
			(start 0.67945 0.3048)
			(end 0.67945 -0.305054)
			(stroke
				(width 0.1)
				(type default)
			)
			(layer "B.Fab")
		)
		(pad "1" smd circle
			(at 0.40005 0 180)
			(size 0 0)
			(layers "B.Cu" "B.Mask" "B.Paste")
			(net "P12V_HSC_ADC_P")
		)
		(pad "2" smd circle
			(at -0.40005 0 180)
			(size 0 0)
			(layers "B.Cu" "B.Mask" "B.Paste")
			(net "P12V_HSC_SENSE2_R4_P")
		)
	)
	(footprint ""
		(layer "B.Cu")
		(at 94.470474 -304.710592 180)
		(property "Reference" "R5031"
			(at 0 0 0)
			(layer "B.SilkS")
			(hide yes)
			(effects
				(font
					(size 1.27 1.27)
				)
				(justify mirror)
			)
		)
		(property "Value" ""
			(at 0 0 0)
			(layer "B.Fab")
			(effects
				(font
					(size 1.27 1.27)
				)
				(justify mirror)
			)
		)
		(duplicate_pad_numbers_are_jumpers no)
		(fp_line
			(start 0.7874 0.4064)
			(end 0.7874 -0.4064)
			(stroke
				(width 0.1524)
				(type default)
			)
			(layer "B.SilkS")
		)
		(fp_line
			(start 0.7874 -0.4064)
			(end -0.7874 -0.4064)
			(stroke
				(width 0.1524)
				(type default)
			)
			(layer "B.SilkS")
		)
		(fp_line
			(start -0.7874 0.4064)
			(end 0.7874 0.4064)
			(stroke
				(width 0.1524)
				(type default)
			)
			(layer "B.SilkS")
		)
		(fp_line
			(start -0.7874 -0.4064)
			(end -0.7874 0.4064)
			(stroke
				(width 0.1524)
				(type default)
			)
			(layer "B.SilkS")
		)
		(fp_line
			(start 0.67945 0.3048)
			(end 0.67945 -0.305054)
			(stroke
				(width 0.1)
				(type default)
			)
			(layer "B.Fab")
		)
		(fp_line
			(start 0.67945 -0.305054)
			(end 0.12065 -0.305054)
			(stroke
				(width 0.1)
				(type default)
			)
			(layer "B.Fab")
		)
		(fp_line
			(start 0.12065 0.3048)
			(end 0.67945 0.3048)
			(stroke
				(width 0.1)
				(type default)
			)
			(layer "B.Fab")
		)
		(fp_line
			(start 0.12065 0.2794)
			(end 0.12065 0.3048)
			(stroke
				(width 0.1)
				(type default)
			)
			(layer "B.Fab")
		)
		(fp_line
			(start 0.12065 -0.2794)
			(end -0.12065 -0.2794)
			(stroke
				(width 0.1)
				(type default)
			)
			(layer "B.Fab")
		)
		(fp_line
			(start 0.12065 -0.305054)
			(end 0.12065 -0.2794)
			(stroke
				(width 0.1)
				(type default)
			)
			(layer "B.Fab")
		)
		(fp_line
			(start -0.120396 0.3048)
			(end -0.120396 0.2794)
			(stroke
				(width 0.1)
				(type default)
			)
			(layer "B.Fab")
		)
		(fp_line
			(start -0.120396 0.2794)
			(end 0.12065 0.2794)
			(stroke
				(width 0.1)
				(type default)
			)
			(layer "B.Fab")
		)
		(fp_line
			(start -0.12065 -0.2794)
			(end -0.12065 -0.3048)
			(stroke
				(width 0.1)
				(type default)
			)
			(layer "B.Fab")
		)
		(fp_line
			(start -0.12065 -0.3048)
			(end -0.67945 -0.3048)
			(stroke
				(width 0.1)
				(type default)
			)
			(layer "B.Fab")
		)
		(fp_line
			(start -0.67945 0.3048)
			(end -0.120396 0.3048)
			(stroke
				(width 0.1)
				(type default)
			)
			(layer "B.Fab")
		)
		(fp_line
			(start -0.67945 -0.3048)
			(end -0.67945 0.3048)
			(stroke
				(width 0.1)
				(type default)
			)
			(layer "B.Fab")
		)
		(pad "1" smd circle
			(at 0.40005 0)
			(size 0 0)
			(layers "B.Cu" "B.Mask" "B.Paste")
			(net "GND")
		)
		(pad "2" smd circle
			(at -0.40005 0)
			(size 0 0)
			(layers "B.Cu" "B.Mask" "B.Paste")
			(net "FM_BMC_READY_N")
		)
	)
)
